# T6G (Grand Teton) — schematic netlist excerpt (pin names and nets, part order shuffled) for the footprints in the layout excerpt that follows; sources: Cadence DE-HDL packaged netlist, KiCad conversion of 04192023_DAF0TMB3IC0_F0TG_MB_C_brd_V02_OCP.brd

R6820  Q_RES  0 5% CHIP  pkg 0201LF  page 277 : A = NCF_A1_CPU0_P0_GND ; B = GND
R8005  Q_RES  33 5% CHIP  pkg 0402LF  page 77 : A = SPI_CPU0_D3 ; B = SPI_CPU0_R1_D3
R660  Q_RES  4.7K 1% EMPTY  pkg 0402LF  page 364 : A = P3V3_AUX ; B = TP_P0V9_RETIMER_CPU1_PMALERT

(kicad_pcb
	(version 20260206)
	(generator "pcbnew")
	(generator_version "10.0")
	(general
		(thickness 1.6)
		(legacy_teardrops no)
	)
	(paper "A4")
	(title_block
		(title "04192023_DAF0TMB3IC0_F0TG_MB_C_brd_V02_OCP.brd")
		(comment 1 "Grand Teton / footprints 1339-1341 of 8354")
	)
	(layers
		(0 "F.Cu" signal "TOP")
		(4 "In1.Cu" signal "GND")
		(6 "In2.Cu" signal "IN1")
		(8 "In3.Cu" signal "GND1")
		(10 "In4.Cu" signal "IN2")
		(12 "In5.Cu" signal "GND2")
		(14 "In6.Cu" signal "IN3")
		(16 "In7.Cu" signal "GND3")
		(18 "In8.Cu" signal "VCC")
		(20 "In9.Cu" signal "VCC1")
		(22 "In10.Cu" signal "GND4")
		(24 "In11.Cu" signal "IN4")
		(26 "In12.Cu" signal "GND5")
		(28 "In13.Cu" signal "IN5")
		(30 "In14.Cu" signal "GND6")
		(32 "In15.Cu" signal "IN6")
		(34 "In16.Cu" signal "GND7")
		(2 "B.Cu" signal "BOTTOM")
		(9 "F.Adhes" user "F.Adhesive")
		(11 "B.Adhes" user "B.Adhesive")
		(13 "F.Paste" user "Package Geometry/Pastemask Top")
		(15 "B.Paste" user "Package Geometry/Pastemask Bottom")
		(5 "F.SilkS" user "Ref Des/Silkscreen Top")
		(7 "B.SilkS" user "Ref Des/Silkscreen Bottom")
		(1 "F.Mask" user "Board Geometry/Soldermask Top")
		(3 "B.Mask" user "Board Geometry/Soldermask Bottom")
		(17 "Dwgs.User" user "User.Drawings")
		(19 "Cmts.User" user "User.Comments")
		(21 "Eco1.User" user "User.Eco1")
		(23 "Eco2.User" user "User.Eco2")
		(25 "Edge.Cuts" user "Board Geometry/Outline")
		(27 "Margin" user)
		(31 "F.CrtYd" user "Package Geometry/Place Bound Top")
		(29 "B.CrtYd" user "Package Geometry/Place Bound Bottom")
		(35 "F.Fab" user "Ref Des/Assembly Top")
		(33 "B.Fab" user "Ref Des/Assembly Bottom")
	)
	(footprint ""
		(layer "F.Cu")
		(at 17.305782 -404.341584 90)
		(property "Reference" "R660"
			(at 0 0 90)
			(layer "F.SilkS")
			(hide yes)
			(effects
				(font
					(size 1.27 1.27)
				)
			)
		)
		(property "Value" ""
			(at 0 0 90)
			(layer "F.Fab")
			(effects
				(font
					(size 1.27 1.27)
				)
			)
		)
		(duplicate_pad_numbers_are_jumpers no)
		(fp_line
			(start 0.7874 -0.4064)
			(end 0.7874 0.4064)
			(stroke
				(width 0.1524)
				(type default)
			)
			(layer "F.SilkS")
		)
		(fp_line
			(start -0.7874 -0.4064)
			(end 0.7874 -0.4064)
			(stroke
				(width 0.1524)
				(type default)
			)
			(layer "F.SilkS")
		)
		(fp_line
			(start 0.7874 0.4064)
			(end -0.7874 0.4064)
			(stroke
				(width 0.1524)
				(type default)
			)
			(layer "F.SilkS")
		)
		(fp_line
			(start -0.7874 0.4064)
			(end -0.7874 -0.4064)
			(stroke
				(width 0.1524)
				(type default)
			)
			(layer "F.SilkS")
		)
		(fp_line
			(start -0.12065 -0.305054)
			(end -0.12065 -0.2794)
			(stroke
				(width 0.1)
				(type default)
			)
			(layer "F.Fab")
		)
		(fp_line
			(start -0.67945 -0.305054)
			(end -0.12065 -0.305054)
			(stroke
				(width 0.1)
				(type default)
			)
			(layer "F.Fab")
		)
		(fp_line
			(start 0.67945 -0.3048)
			(end 0.67945 0.3048)
			(stroke
				(width 0.1)
				(type default)
			)
			(layer "F.Fab")
		)
		(fp_line
			(start 0.12065 -0.3048)
			(end 0.67945 -0.3048)
			(stroke
				(width 0.1)
				(type default)
			)
			(layer "F.Fab")
		)
		(fp_line
			(start 0.12065 -0.2794)
			(end 0.12065 -0.3048)
			(stroke
				(width 0.1)
				(type default)
			)
			(layer "F.Fab")
		)
		(fp_line
			(start -0.12065 -0.2794)
			(end 0.12065 -0.2794)
			(stroke
				(width 0.1)
				(type default)
			)
			(layer "F.Fab")
		)
		(fp_line
			(start 0.120396 0.2794)
			(end -0.12065 0.2794)
			(stroke
				(width 0.1)
				(type default)
			)
			(layer "F.Fab")
		)
		(fp_line
			(start -0.12065 0.2794)
			(end -0.12065 0.3048)
			(stroke
				(width 0.1)
				(type default)
			)
			(layer "F.Fab")
		)
		(fp_line
			(start 0.67945 0.3048)
			(end 0.120396 0.3048)
			(stroke
				(width 0.1)
				(type default)
			)
			(layer "F.Fab")
		)
		(fp_line
			(start 0.120396 0.3048)
			(end 0.120396 0.2794)
			(stroke
				(width 0.1)
				(type default)
			)
			(layer "F.Fab")
		)
		(fp_line
			(start -0.12065 0.3048)
			(end -0.67945 0.3048)
			(stroke
				(width 0.1)
				(type default)
			)
			(layer "F.Fab")
		)
		(fp_line
			(start -0.67945 0.3048)
			(end -0.67945 -0.305054)
			(stroke
				(width 0.1)
				(type default)
			)
			(layer "F.Fab")
		)
		(pad "1" smd circle
			(at -0.40005 0 90)
			(size 0 0)
			(layers "F.Cu" "F.Mask" "F.Paste")
			(net "P3V3_AUX")
		)
		(pad "2" smd circle
			(at 0.40005 0 90)
			(size 0 0)
			(layers "F.Cu" "F.Mask" "F.Paste")
			(net "TP_P0V9_RETIMER_CPU1_PMALERT")
		)
	)
	(footprint ""
		(layer "F.Cu")
		(at 265.176 -136.652 180)
		(property "Reference" "R8005"
			(at 0 0 180)
			(layer "F.SilkS")
			(hide yes)
			(effects
				(font
					(size 1.27 1.27)
				)
			)
		)
		(property "Value" ""
			(at 0 0 180)
			(layer "F.Fab")
			(effects
				(font
					(size 1.27 1.27)
				)
			)
		)
		(duplicate_pad_numbers_are_jumpers no)
		(fp_line
			(start 0.7874 0.4064)
			(end -0.7874 0.4064)
			(stroke
				(width 0.1524)
				(type default)
			)
			(layer "F.SilkS")
		)
		(fp_line
			(start 0.7874 -0.4064)
			(end 0.7874 0.4064)
			(stroke
				(width 0.1524)
				(type default)
			)
			(layer "F.SilkS")
		)
		(fp_line
			(start -0.7874 0.4064)
			(end -0.7874 -0.4064)
			(stroke
				(width 0.1524)
				(type default)
			)
			(layer "F.SilkS")
		)
		(fp_line
			(start -0.7874 -0.4064)
			(end 0.7874 -0.4064)
			(stroke
				(width 0.1524)
				(type default)
			)
			(layer "F.SilkS")
		)
		(fp_line
			(start 0.67945 0.3048)
			(end 0.120396 0.3048)
			(stroke
				(width 0.1)
				(type default)
			)
			(layer "F.Fab")
		)
		(fp_line
			(start 0.67945 -0.3048)
			(end 0.67945 0.3048)
			(stroke
				(width 0.1)
				(type default)
			)
			(layer "F.Fab")
		)
		(fp_line
			(start 0.12065 -0.2794)
			(end 0.12065 -0.3048)
			(stroke
				(width 0.1)
				(type default)
			)
			(layer "F.Fab")
		)
		(fp_line
			(start 0.12065 -0.3048)
			(end 0.67945 -0.3048)
			(stroke
				(width 0.1)
				(type default)
			)
			(layer "F.Fab")
		)
		(fp_line
			(start 0.120396 0.3048)
			(end 0.120396 0.2794)
			(stroke
				(width 0.1)
				(type default)
			)
			(layer "F.Fab")
		)
		(fp_line
			(start 0.120396 0.2794)
			(end -0.12065 0.2794)
			(stroke
				(width 0.1)
				(type default)
			)
			(layer "F.Fab")
		)
		(fp_line
			(start -0.12065 0.3048)
			(end -0.67945 0.3048)
			(stroke
				(width 0.1)
				(type default)
			)
			(layer "F.Fab")
		)
		(fp_line
			(start -0.12065 0.2794)
			(end -0.12065 0.3048)
			(stroke
				(width 0.1)
				(type default)
			)
			(layer "F.Fab")
		)
		(fp_line
			(start -0.12065 -0.2794)
			(end 0.12065 -0.2794)
			(stroke
				(width 0.1)
				(type default)
			)
			(layer "F.Fab")
		)
		(fp_line
			(start -0.12065 -0.305054)
			(end -0.12065 -0.2794)
			(stroke
				(width 0.1)
				(type default)
			)
			(layer "F.Fab")
		)
		(fp_line
			(start -0.67945 0.3048)
			(end -0.67945 -0.305054)
			(stroke
				(width 0.1)
				(type default)
			)
			(layer "F.Fab")
		)
		(fp_line
			(start -0.67945 -0.305054)
			(end -0.12065 -0.305054)
			(stroke
				(width 0.1)
				(type default)
			)
			(layer "F.Fab")
		)
		(pad "1" smd circle
			(at -0.40005 0 180)
			(size 0 0)
			(layers "F.Cu" "F.Mask" "F.Paste")
			(net "SPI_CPU0_D3")
		)
		(pad "2" smd circle
			(at 0.40005 0 180)
			(size 0 0)
			(layers "F.Cu" "F.Mask" "F.Paste")
			(net "SPI_CPU0_R1_D3")
		)
	)
	(footprint ""
		(layer "F.Cu")
		(at 324.981062 -402.9202 -90)
		(property "Reference" "R6820"
			(at 0 0 270)
			(layer "F.SilkS")
			(hide yes)
			(effects
				(font
					(size 1.27 1.27)
				)
			)
		)
		(property "Value" ""
			(at 0 0 270)
			(layer "F.Fab")
			(effects
				(font
					(size 1.27 1.27)
				)
			)
		)
		(duplicate_pad_numbers_are_jumpers no)
		(fp_line
			(start -0.32512 0.175006)
			(end -0.32512 -0.175006)
			(stroke
				(width 0.1)
				(type default)
			)
			(layer "F.Fab")
		)
		(fp_line
			(start 0.32512 0.175006)
			(end -0.32512 0.175006)
			(stroke
				(width 0.1)
				(type default)
			)
			(layer "F.Fab")
		)
		(fp_line
			(start -0.32512 -0.175006)
			(end 0.32512 -0.175006)
			(stroke
				(width 0.1)
				(type default)
			)
			(layer "F.Fab")
		)
		(fp_line
			(start 0.32512 -0.175006)
			(end 0.32512 0.175006)
			(stroke
				(width 0.1)
				(type default)
			)
			(layer "F.Fab")
		)
		(pad "1" smd rect
			(at -0.2667 0 270)
			(size 0.3048 0.381)
			(layers "F.Cu" "F.Mask" "F.Paste")
			(net "NCF_A1_CPU0_P0_GND")
		)
		(pad "2" smd rect
			(at 0.2667 0 90)
			(size 0.3048 0.381)
			(layers "F.Cu" "F.Mask" "F.Paste")
			(net "GND")
		)
	)
)
